(kicad_pcb
	(version 20240108)
	(generator "pcbnew")
	(generator_version "8.0")
	(general
		(thickness 1.62)
		(legacy_teardrops no)
	)
	(paper "A4")
	(title_block
		(title "Jetson Orin Baseboard")
		(date "2025-03-12")
		(rev "1.3.4")
		(company "Antmicro Ltd")
		(comment 1 "www.antmicro.com")
		(comment 9 "footprints 356-360 of 677")
	)
	(layers
		(0 "F.Cu" signal)
		(1 "In1.Cu" signal)
		(2 "In2.Cu" signal)
		(3 "In3.Cu" signal)
		(4 "In4.Cu" jumper)
		(5 "In5.Cu" signal)
		(6 "In6.Cu" signal)
		(31 "B.Cu" signal)
		(32 "B.Adhes" user "B.Adhesive")
		(33 "F.Adhes" user "F.Adhesive")
		(34 "B.Paste" user)
		(35 "F.Paste" user)
		(36 "B.SilkS" user "B.Silkscreen")
		(37 "F.SilkS" user "F.Silkscreen")
		(38 "B.Mask" user)
		(39 "F.Mask" user)
		(40 "Dwgs.User" user "User.Drawings")
		(41 "Cmts.User" user "User.Comments")
		(42 "Eco1.User" user "User.Eco1")
		(43 "Eco2.User" user "User.Eco2")
		(44 "Edge.Cuts" user)
		(45 "Margin" user)
		(46 "B.CrtYd" user "B.Courtyard")
		(47 "F.CrtYd" user "F.Courtyard")
		(48 "B.Fab" user)
		(49 "F.Fab" user)
	)
	(footprint "antmicro-footprints:R_0402_1005Metric"
		(layer "B.Cu")
		(at 111.6 88.02 90)
		(descr "Resistor SMD 0402")
		(tags "resistor SMD 0402")
		(property "Reference" "R37"
			(at 1.14 1.38 -90)
			(layer "B.SilkS")
			(effects
				(font
					(size 0.7 0.7)
					(thickness 0.15)
				)
				(justify left bottom mirror)
			)
		)
		(property "Value" "R_47k_0402"
			(at 0 -1.4 -90)
			(layer "B.Fab")
			(effects
				(font
					(size 0.7 0.7)
					(thickness 0.15)
				)
				(justify left bottom mirror)
			)
		)
		(property "Footprint" "antmicro-footprints:R_0402_1005Metric"
			(at 0 0 90)
			(layer "F.Fab")
			(hide yes)
			(effects
				(font
					(size 1.27 1.27)
					(thickness 0.15)
				)
			)
		)
		(property "Datasheet" "https://www.bourns.com/docs/product-datasheets/cr.pdf"
			(at 0 0 90)
			(layer "F.Fab")
			(hide yes)
			(effects
				(font
					(size 1.27 1.27)
					(thickness 0.15)
				)
			)
		)
		(property "Author" "Antmicro"
			(at 199.62 -23.58 0)
			(layer "B.Fab")
			(hide yes)
			(effects
				(font
					(size 1 1)
					(thickness 0.15)
				)
				(justify mirror)
			)
		)
		(property "License" "Apache-2.0"
			(at 199.62 -23.58 0)
			(layer "B.Fab")
			(hide yes)
			(effects
				(font
					(size 1 1)
					(thickness 0.15)
				)
				(justify mirror)
			)
		)
		(property "MPN" "CR0402-FX-4702GLF"
			(at 199.62 -23.58 0)
			(layer "B.Fab")
			(hide yes)
			(effects
				(font
					(size 1 1)
					(thickness 0.15)
				)
				(justify mirror)
			)
		)
		(property "Manufacturer" "Bourns"
			(at 199.62 -23.58 0)
			(layer "B.Fab")
			(hide yes)
			(effects
				(font
					(size 1 1)
					(thickness 0.15)
				)
				(justify mirror)
			)
		)
		(property "Tolerance" "1%"
			(at 199.62 -23.58 0)
			(layer "B.Fab")
			(hide yes)
			(effects
				(font
					(size 1 1)
					(thickness 0.15)
				)
				(justify mirror)
			)
		)
		(property "Val" "47k"
			(at 199.62 -23.58 0)
			(layer "B.Fab")
			(hide yes)
			(effects
				(font
					(size 1 1)
					(thickness 0.15)
				)
				(justify mirror)
			)
		)
		(sheetname "M.2")
		(sheetfile "m-2.kicad_sch")
		(attr smd exclude_from_pos_files exclude_from_bom dnp)
		(fp_rect
			(start -0.925 0.47)
			(end 0.925 -0.47)
			(stroke
				(width 0.05)
				(type default)
			)
			(fill none)
			(layer "B.CrtYd")
		)
		(fp_rect
			(start -0.5 0.25)
			(end 0.5 -0.25)
			(stroke
				(width 0.15)
				(type solid)
			)
			(fill none)
			(layer "B.Fab")
		)
		(fp_text user "License: Apache-2.0"
			(at -0.95 -5.169 -90)
			(layer "B.Fab")
			(hide yes)
			(effects
				(font
					(size 0.7 0.7)
					(thickness 0.15)
				)
				(justify left bottom mirror)
			)
		)
		(fp_text user "Author: Antmicro"
			(at -0.95 -4.169 -90)
			(layer "B.Fab")
			(hide yes)
			(effects
				(font
					(size 0.7 0.7)
					(thickness 0.15)
				)
				(justify left bottom mirror)
			)
		)
		(fp_text user "${REFERENCE}"
			(at -0.95 -3.168 -90)
			(layer "B.Fab")
			(hide yes)
			(effects
				(font
					(size 0.7 0.7)
					(thickness 0.15)
				)
				(justify left bottom mirror)
			)
		)
		(pad "1" smd roundrect
			(at -0.48 0 90)
			(size 0.59 0.64)
			(layers "B.Cu" "B.Paste" "B.Mask")
			(roundrect_rratio 0.25)
			(net 87 "+3V3")
			(pintype "passive")
		)
		(pad "2" smd roundrect
			(at 0.48 0 90)
			(size 0.59 0.64)
			(layers "B.Cu" "B.Paste" "B.Mask")
			(roundrect_rratio 0.25)
			(net 247 "/M.2/~{M2_M_PERST}")
			(pintype "passive")
		)
	)
	(footprint "antmicro-footprints:TP_SMD_0.75mm"
		(layer "B.Cu")
		(at 75.28 75.395 180)
		(property "Reference" "TP44"
			(at -0.37 0.51 0)
			(layer "B.SilkS")
			(effects
				(font
					(size 0.7 0.7)
					(thickness 0.15)
				)
				(justify left bottom mirror)
			)
		)
		(property "Value" "TP_0.75mm_SMD"
			(at 0 -1.2 0)
			(layer "B.Fab")
			(effects
				(font
					(size 0.7 0.7)
					(thickness 0.15)
				)
				(justify left bottom mirror)
			)
		)
		(property "Footprint" "antmicro-footprints:TP_SMD_0.75mm"
			(at 0 0 180)
			(layer "F.Fab")
			(hide yes)
			(effects
				(font
					(size 1.27 1.27)
					(thickness 0.15)
				)
			)
		)
		(property "Author" "Antmicro"
			(at 150.56 150.79 0)
			(layer "B.Fab")
			(hide yes)
			(effects
				(font
					(size 1 1)
					(thickness 0.15)
				)
				(justify mirror)
			)
		)
		(property "License" "Apache-2.0"
			(at 150.56 150.79 0)
			(layer "B.Fab")
			(hide yes)
			(effects
				(font
					(size 1 1)
					(thickness 0.15)
				)
				(justify mirror)
			)
		)
		(property "MPN" ""
			(at 150.56 150.79 0)
			(layer "B.Fab")
			(hide yes)
			(effects
				(font
					(size 1 1)
					(thickness 0.15)
				)
				(justify mirror)
			)
		)
		(property "Manufacturer" ""
			(at 150.56 150.79 0)
			(layer "B.Fab")
			(hide yes)
			(effects
				(font
					(size 1 1)
					(thickness 0.15)
				)
				(justify mirror)
			)
		)
		(sheetname "SoM")
		(sheetfile "som.kicad_sch")
		(attr exclude_from_pos_files exclude_from_bom)
		(fp_circle
			(center 0 0)
			(end 0.475 0)
			(stroke
				(width 0.05)
				(type default)
			)
			(fill none)
			(layer "B.CrtYd")
		)
		(fp_text user "Author: Antmicro"
			(at -0.4 -3.901 0)
			(layer "B.Fab")
			(hide yes)
			(effects
				(font
					(size 0.7 0.7)
					(thickness 0.15)
				)
				(justify left bottom mirror)
			)
		)
		(fp_text user "${REFERENCE}"
			(at -0.4 -2.7 0)
			(layer "B.Fab")
			(hide yes)
			(effects
				(font
					(size 0.7 0.7)
					(thickness 0.15)
				)
				(justify left bottom mirror)
			)
		)
		(fp_text user "License: Apache-2.0"
			(at -0.4 -5.101 0)
			(layer "B.Fab")
			(hide yes)
			(effects
				(font
					(size 0.7 0.7)
					(thickness 0.15)
				)
				(justify left bottom mirror)
			)
		)
		(pad "1" smd circle
			(at 0 0 180)
			(size 0.75 0.75)
			(layers "B.Cu" "B.Mask")
			(net 750 "Net-(J15A-CLK_32K_OUT)")
			(pinfunction "1")
			(pintype "passive")
		)
	)
	(footprint "antmicro-footprints:LED_0603_1608Metric_G"
		(layer "B.Cu")
		(at 108.4 71.8 180)
		(descr "LED SMD 0603 Green")
		(tags "LED SMD 0603 Green")
		(property "Reference" "D25"
			(at 1.1 -0.45 0)
			(layer "B.SilkS")
			(effects
				(font
					(size 0.7 0.7)
					(thickness 0.15)
				)
				(justify left bottom mirror)
			)
		)
		(property "Value" "LED_G_0603_LTST-C190GKT"
			(at -0.001 -1.599 0)
			(layer "B.Fab")
			(effects
				(font
					(size 0.7 0.7)
					(thickness 0.15)
				)
				(justify left bottom mirror)
			)
		)
		(property "Footprint" "antmicro-footprints:LED_0603_1608Metric_G"
			(at 0 0 180)
			(layer "F.Fab")
			(hide yes)
			(effects
				(font
					(size 1.27 1.27)
					(thickness 0.15)
				)
			)
		)
		(property "Datasheet" "https://media.digikey.com/pdf/Data%20Sheets/Lite-On%20PDFs/LTST-C190GKT.pdf"
			(at 0 0 180)
			(layer "F.Fab")
			(hide yes)
			(effects
				(font
					(size 1.27 1.27)
					(thickness 0.15)
				)
			)
		)
		(property "Author" "Antmicro"
			(at 216.8 143.6 0)
			(layer "B.Fab")
			(hide yes)
			(effects
				(font
					(size 1 1)
					(thickness 0.15)
				)
				(justify mirror)
			)
		)
		(property "Color" "Green"
			(at 216.8 143.6 0)
			(layer "B.Fab")
			(hide yes)
			(effects
				(font
					(size 1 1)
					(thickness 0.15)
				)
				(justify mirror)
			)
		)
		(property "License" "Apache-2.0"
			(at 216.8 143.6 0)
			(layer "B.Fab")
			(hide yes)
			(effects
				(font
					(size 1 1)
					(thickness 0.15)
				)
				(justify mirror)
			)
		)
		(property "MPN" "LTST-C190GKT"
			(at 216.8 143.6 0)
			(layer "B.Fab")
			(hide yes)
			(effects
				(font
					(size 1 1)
					(thickness 0.15)
				)
				(justify mirror)
			)
		)
		(property "Manufacturer" "Lite-On"
			(at 216.8 143.6 0)
			(layer "B.Fab")
			(hide yes)
			(effects
				(font
					(size 1 1)
					(thickness 0.15)
				)
				(justify mirror)
			)
		)
		(sheetname "CSI")
		(sheetfile "csi.kicad_sch")
		(attr smd)
		(fp_line
			(start 0.24 -0.001)
			(end 0.105328 -0.001008)
			(stroke
				(width 0.1)
				(type solid)
			)
			(layer "B.SilkS")
		)
		(fp_line
			(start 0.105328 0.198992)
			(end 0.105328 -0.201008)
			(stroke
				(width 0.1)
				(type solid)
			)
			(layer "B.SilkS")
		)
		(fp_line
			(start 0.105328 0.198992)
			(end -0.094672 -0.001008)
			(stroke
				(width 0.1)
				(type solid)
			)
			(layer "B.SilkS")
		)
		(fp_line
			(start -0.094672 0.198992)
			(end -0.094672 -0.201008)
			(stroke
				(width 0.1)
				(type solid)
			)
			(layer "B.SilkS")
		)
		(fp_line
			(start -0.094672 -0.001008)
			(end 0.105328 -0.201008)
			(stroke
				(width 0.1)
				(type solid)
			)
			(layer "B.SilkS")
		)
		(fp_line
			(start -0.22 0.35)
			(end 0.22 0.35)
			(stroke
				(width 0.15)
				(type solid)
			)
			(layer "B.SilkS")
		)
		(fp_line
			(start -0.22 -0.35)
			(end 0.22 -0.35)
			(stroke
				(width 0.15)
				(type solid)
			)
			(layer "B.SilkS")
		)
		(fp_line
			(start -0.24 -0.001008)
			(end -0.094672 -0.001008)
			(stroke
				(width 0.1)
				(type solid)
			)
			(layer "B.SilkS")
		)
		(fp_line
			(start -1.18 -0.321)
			(end -1.18 0.319)
			(stroke
				(width 0.15)
				(type solid)
			)
			(layer "B.SilkS")
		)
		(fp_rect
			(start 1.25 -0.65)
			(end -1.25 0.65)
			(stroke
				(width 0.05)
				(type solid)
			)
			(fill none)
			(layer "B.CrtYd")
		)
		(fp_line
			(start 0.201 0.202)
			(end 0.201 0)
			(stroke
				(width 0.15)
				(type solid)
			)
			(layer "B.Fab")
		)
		(fp_line
			(start 0.201 0)
			(end 0.599 0)
			(stroke
				(width 0.15)
				(type solid)
			)
			(layer "B.Fab")
		)
		(fp_line
			(start 0.201 0)
			(end 0.201 -0.2)
			(stroke
				(width 0.15)
				(type solid)
			)
			(layer "B.Fab")
		)
		(fp_line
			(start 0.201 -0.2)
			(end -0.101 0)
			(stroke
				(width 0.15)
				(type solid)
			)
			(layer "B.Fab")
		)
		(fp_line
			(start -0.101 0)
			(end 0.201 0.202)
			(stroke
				(width 0.15)
				(type solid)
			)
			(layer "B.Fab")
		)
		(fp_line
			(start -0.199 -0.1)
			(end -0.199 0.202)
			(stroke
				(width 0.15)
				(type solid)
			)
			(layer "B.Fab")
		)
		(fp_line
			(start -0.199 -0.1)
			(end -0.199 -0.2)
			(stroke
				(width 0.15)
				(type solid)
			)
			(layer "B.Fab")
		)
		(fp_line
			(start -0.597 0)
			(end -0.199 0)
			(stroke
				(width 0.15)
				(type solid)
			)
			(layer "B.Fab")
		)
		(fp_rect
			(start 0.848 -0.4)
			(end -0.85 0.402)
			(stroke
				(width 0.15)
				(type solid)
			)
			(fill none)
			(layer "B.Fab")
		)
		(fp_text user "License: Apache-2.0"
			(at -1.4224 -3.599 0)
			(layer "B.Fab")
			(hide yes)
			(effects
				(font
					(size 0.7 0.7)
					(thickness 0.15)
				)
				(justify left bottom mirror)
			)
		)
		(fp_text user "${REFERENCE}"
			(at -1.4224 -5.999 0)
			(layer "B.Fab")
			(hide yes)
			(effects
				(font
					(size 0.7 0.7)
					(thickness 0.15)
				)
				(justify left bottom mirror)
			)
		)
		(fp_text user "Author: Antmicro"
			(at -1.4224 -4.799 0)
			(layer "B.Fab")
			(hide yes)
			(effects
				(font
					(size 0.7 0.7)
					(thickness 0.15)
				)
				(justify left bottom mirror)
			)
		)
		(pad "1" smd roundrect
			(at -0.7 0)
			(size 0.8 1)
			(layers "B.Cu" "B.Paste" "B.Mask")
			(roundrect_rratio 0.2)
			(net 1 "GND")
			(pinfunction "C")
			(pintype "passive")
		)
		(pad "2" smd roundrect
			(at 0.7 0)
			(size 0.8 1)
			(layers "B.Cu" "B.Paste" "B.Mask")
			(roundrect_rratio 0.2)
			(net 162 "Net-(D25-A)")
			(pinfunction "A")
			(pintype "passive")
		)
	)
	(footprint "antmicro-footprints:R_0402_1005Metric"
		(layer "B.Cu")
		(at 137.7 116.55)
		(descr "Resistor SMD 0402")
		(tags "resistor SMD 0402")
		(property "Reference" "R7"
			(at -0.75 0.45 180)
			(layer "B.SilkS")
			(effects
				(font
					(size 0.7 0.7)
					(thickness 0.15)
				)
				(justify left bottom mirror)
			)
		)
		(property "Value" "R_4k7_0402"
			(at 0 -1.4 180)
			(layer "B.Fab")
			(effects
				(font
					(size 0.7 0.7)
					(thickness 0.15)
				)
				(justify left bottom mirror)
			)
		)
		(property "Footprint" "antmicro-footprints:R_0402_1005Metric"
			(at 0 0 0)
			(layer "F.Fab")
			(hide yes)
			(effects
				(font
					(size 1.27 1.27)
					(thickness 0.15)
				)
			)
		)
		(property "Datasheet" "https://www.bourns.com/docs/product-datasheets/cr.pdf"
			(at 0 0 0)
			(layer "F.Fab")
			(hide yes)
			(effects
				(font
					(size 1.27 1.27)
					(thickness 0.15)
				)
			)
		)
		(property "Author" "Antmicro"
			(at 0 0 0)
			(layer "B.Fab")
			(hide yes)
			(effects
				(font
					(size 1 1)
					(thickness 0.15)
				)
				(justify mirror)
			)
		)
		(property "License" "Apache-2.0"
			(at 0 0 0)
			(layer "B.Fab")
			(hide yes)
			(effects
				(font
					(size 1 1)
					(thickness 0.15)
				)
				(justify mirror)
			)
		)
		(property "MPN" "CR0402-FX-4701GLF"
			(at 0 0 0)
			(layer "B.Fab")
			(hide yes)
			(effects
				(font
					(size 1 1)
					(thickness 0.15)
				)
				(justify mirror)
			)
		)
		(property "Manufacturer" "Bourns"
			(at 0 0 0)
			(layer "B.Fab")
			(hide yes)
			(effects
				(font
					(size 1 1)
					(thickness 0.15)
				)
				(justify mirror)
			)
		)
		(property "Tolerance" "1%"
			(at 0 0 0)
			(layer "B.Fab")
			(hide yes)
			(effects
				(font
					(size 1 1)
					(thickness 0.15)
				)
				(justify mirror)
			)
		)
		(property "Val" "4k7"
			(at 0 0 0)
			(layer "B.Fab")
			(hide yes)
			(effects
				(font
					(size 1 1)
					(thickness 0.15)
				)
				(justify mirror)
			)
		)
		(sheetname "CSI")
		(sheetfile "csi.kicad_sch")
		(attr smd)
		(fp_rect
			(start -0.925 0.47)
			(end 0.925 -0.47)
			(stroke
				(width 0.05)
				(type default)
			)
			(fill none)
			(layer "B.CrtYd")
		)
		(fp_rect
			(start -0.5 0.25)
			(end 0.5 -0.25)
			(stroke
				(width 0.15)
				(type solid)
			)
			(fill none)
			(layer "B.Fab")
		)
		(fp_text user "License: Apache-2.0"
			(at -0.95 -5.169 180)
			(layer "B.Fab")
			(hide yes)
			(effects
				(font
					(size 0.7 0.7)
					(thickness 0.15)
				)
				(justify left bottom mirror)
			)
		)
		(fp_text user "Author: Antmicro"
			(at -0.95 -4.169 180)
			(layer "B.Fab")
			(hide yes)
			(effects
				(font
					(size 0.7 0.7)
					(thickness 0.15)
				)
				(justify left bottom mirror)
			)
		)
		(fp_text user "${REFERENCE}"
			(at -0.95 -3.168 180)
			(layer "B.Fab")
			(hide yes)
			(effects
				(font
					(size 0.7 0.7)
					(thickness 0.15)
				)
				(justify left bottom mirror)
			)
		)
		(pad "1" smd roundrect
			(at -0.48 0)
			(size 0.59 0.64)
			(layers "B.Cu" "B.Paste" "B.Mask")
			(roundrect_rratio 0.25)
			(net 1 "GND")
			(pintype "passive")
		)
		(pad "2" smd roundrect
			(at 0.48 0)
			(size 0.59 0.64)
			(layers "B.Cu" "B.Paste" "B.Mask")
			(roundrect_rratio 0.25)
			(net 334 "/CSI/CSIA_5V_ISET")
			(pintype "passive")
		)
	)
	(footprint "antmicro-footprints:R_0402_1005Metric"
		(layer "B.Cu")
		(at 65.925 110.275 90)
		(descr "Resistor SMD 0402")
		(tags "resistor SMD 0402")
		(property "Reference" "R44"
			(at -0.935 0.305 -90)
			(layer "B.SilkS")
			(effects
				(font
					(size 0.7 0.7)
					(thickness 0.15)
				)
				(justify left bottom mirror)
			)
		)
		(property "Value" "R_10k_0402"
			(at 0 -1.4 -90)
			(layer "B.Fab")
			(effects
				(font
					(size 0.7 0.7)
					(thickness 0.15)
				)
				(justify left bottom mirror)
			)
		)
		(property "Footprint" "antmicro-footprints:R_0402_1005Metric"
			(at 0 0 90)
			(layer "F.Fab")
			(hide yes)
			(effects
				(font
					(size 1.27 1.27)
					(thickness 0.15)
				)
			)
		)
		(property "Datasheet" "https://www.bourns.com/docs/product-datasheets/cr.pdf"
			(at 0 0 90)
			(layer "F.Fab")
			(hide yes)
			(effects
				(font
					(size 1.27 1.27)
					(thickness 0.15)
				)
			)
		)
		(property "Author" "Antmicro"
			(at 176.2 44.35 0)
			(layer "B.Fab")
			(hide yes)
			(effects
				(font
					(size 1 1)
					(thickness 0.15)
				)
				(justify mirror)
			)
		)
		(property "License" "Apache-2.0"
			(at 176.2 44.35 0)
			(layer "B.Fab")
			(hide yes)
			(effects
				(font
					(size 1 1)
					(thickness 0.15)
				)
				(justify mirror)
			)
		)
		(property "MPN" "CR0402-FX-1002GLF"
			(at 176.2 44.35 0)
			(layer "B.Fab")
			(hide yes)
			(effects
				(font
					(size 1 1)
					(thickness 0.15)
				)
				(justify mirror)
			)
		)
		(property "Manufacturer" "Bourns"
			(at 176.2 44.35 0)
			(layer "B.Fab")
			(hide yes)
			(effects
				(font
					(size 1 1)
					(thickness 0.15)
				)
				(justify mirror)
			)
		)
		(property "Tolerance" "1%"
			(at 176.2 44.35 0)
			(layer "B.Fab")
			(hide yes)
			(effects
				(font
					(size 1 1)
					(thickness 0.15)
				)
				(justify mirror)
			)
		)
		(property "Val" "10k"
			(at 176.2 44.35 0)
			(layer "B.Fab")
			(hide yes)
			(effects
				(font
					(size 1 1)
					(thickness 0.15)
				)
				(justify mirror)
			)
		)
		(sheetname "USB Debug, DP")
		(sheetfile "usb.kicad_sch")
		(attr smd)
		(fp_rect
			(start -0.925 0.47)
			(end 0.925 -0.47)
			(stroke
				(width 0.05)
				(type default)
			)
			(fill none)
			(layer "B.CrtYd")
		)
		(fp_rect
			(start -0.5 0.25)
			(end 0.5 -0.25)
			(stroke
				(width 0.15)
				(type solid)
			)
			(fill none)
			(layer "B.Fab")
		)
		(fp_text user "${REFERENCE}"
			(at -0.95 -3.168 -90)
			(layer "B.Fab")
			(hide yes)
			(effects
				(font
					(size 0.7 0.7)
					(thickness 0.15)
				)
				(justify left bottom mirror)
			)
		)
		(fp_text user "Author: Antmicro"
			(at -0.95 -4.169 -90)
			(layer "B.Fab")
			(hide yes)
			(effects
				(font
					(size 0.7 0.7)
					(thickness 0.15)
				)
				(justify left bottom mirror)
			)
		)
		(fp_text user "License: Apache-2.0"
			(at -0.95 -5.169 -90)
			(layer "B.Fab")
			(hide yes)
			(effects
				(font
					(size 0.7 0.7)
					(thickness 0.15)
				)
				(justify left bottom mirror)
			)
		)
		(pad "1" smd roundrect
			(at -0.48 0 90)
			(size 0.59 0.64)
			(layers "B.Cu" "B.Paste" "B.Mask")
			(roundrect_rratio 0.25)
			(net 134 "/USB Debug, DP/PDC_LDO_3V3")
			(pintype "passive")
		)
		(pad "2" smd roundrect
			(at 0.48 0 90)
			(size 0.59 0.64)
			(layers "B.Cu" "B.Paste" "B.Mask")
			(roundrect_rratio 0.25)
			(net 287 "/USB Debug, DP/PDC_ADCIN2")
			(pintype "passive")
		)
	)
)
